# Bryce Canyon_ME BOM MP.xlsx — System BOM (bom)
| Wiwynn |  |  |  |  |  | TRITON |  |  |  |  |  |  |  |  |  |  |
| Model: TRITON |  |  |  |  |  |  |  |  |  |  |  |  |  |  |  |  |
| Project Code.: |  |  |  |  |  | Version:1.1 |  |  |  |  |  |  |  |  |  |  |
| Vendor: |  | 料號顏色區分: 藍色  初始料號 紅色  更變料號 黑色  沿用料號 |  |  |  | 2017/03/23 |  |  |  |  |  |  |  |  |  |  |
| No | Level | WW P/N EVT | WW P/N DVT | WW P/N DVT2 | WW P/N MP | Description | Part Name | Picture | Tool status | Type 4 Usage/System | Type 5 Usage/System | Type 7 Headnode Usage/System | Type 7 JBOD Usage/System | Material/Finish | Type | Suppier |
|  |  |  |  |  |  |  |  |  |  |  |  |  |  |  | Assy/Metal/ Plastic/Purchase/Cable |  |
|  | 1 | B60.01108.0001 | B60.0110T.0001 | B60.0110T.0011 | B60.0110T.0021 | ASSY MAIN CHASSIS TYPE4/7 JBOD BC MP | 00-ACKBAR TOP ASSEMBLY |  |  | 1 |  |  | 1 | Chassis | Assy | 長江 |
|  | 1 | B60.01101.0001 | B60.0110S.0001 | B60.0110S.0011 | B60.0110S.0021 | ASSY MAIN CHASSIS TYPE5 BC MP | 00-ACKBAR TOP ASSEMBLY |  |  |  | 1 |  |  | Chassis | Assy | 長江 |
|  | 1 | B60.01109.0001 | B60.0110U.0001 | B60.0110U.0011 | B60.0110U.0021 | ASSY MAIN CHASSIS TYPE7 HEADNODE BC MP | 00-ACKBAR TOP ASSEMBLY |  |  |  |  | 1 |  | Chassis | Assy | 長江 |
|  | 1 | B34.0110P.0001 | B34.0110P.0001 | B34.0110P.0001 | B60.01112.0001 | ASSY FDPB SUPPORT BKT BRCA | ASSY FDPB SUPPORT BKT  TRITON |  | PVT new tool | 4 | 4 | 4 | 4 | ASSY | Assy | 長江 |
|  | 1 | B42.0110Z.0001 | B42.0110Z.0001 | B42.0110Z.0001 | B42.0110Z.1001 | CVR DPB SUPPORT AIR DUCT BRCA | FR_DPB_SUPPORT_AIR_DUCT  TRITON |  | PVT new tool | 2 | 2 | 2 | 2 | ASSY | Plastic | 長江 |
|  | 1 |  | B42.0111O.0001 | B42.0111O.0001 | B60.01111.0001 | ASSY DPB BAFFLE BRCA |  |  | PVT new tool | 1 | 1 | 1 | 1 | PC+ABS/NA Color:Black | Plastic | 長江 |
|  | 1 | B42.0111A.0001 | B42.0111A.0001 | B42.0111A.0001 | B42.00X0K.0001 | 3.5" DUMMY HDD | DUMMY HDD |  | PVT new tool |  |  | 2 | 2 | PC+ABS/NA Color:Black | Plastic | 晟銘 |
|  | 1 |  | B33.01115.0001 | B33.01115.0001 | B33.01115.1001 | BRKT FRONT PANEL MINISAS HD BRCA | FRONT PANEL SAS HD BRACKET |  | PVT new tool | 1 |  |  | 1 | SGCC(T=1.0mm)/NA | Metal | 長江 |
|  | System | B50.01105.0001 | B50.0110U.0001 | B50.0110U.0001 | B50.0110U.0001 | C.A. BAR CABLE DVT FCI | Vendor P/N :10130664-3C0059HLF-REV-8 |  |  | 1 | 1 | 1 | 1 | Cable | Cable | FCI |
|  | System | B50.01107.0001 | B50.0110S.0001 | B50.0110S.0001 | B50.0110S.0011 | C.A. MINISAS HD INT/ EXT-R APH | Vendor P/N :GTR797836110G1HR |  |  | 1 |  |  | 1 | Cable | Cable | Amphenol |
|  | System |  | B50.0110T.0001 | B50.0110T.0001 | B50.0110T.0011 | C.A. MINISAS HD INT/ EXT-L APH | Vendor P/N : GTR797836110GHR |  |  | 1 |  |  | 1 | Cable | Cable | Amphenol |
|  | System | B50.0110O.0001 | B50.0110V.0001 | B50.0110V.0001 | B50.0110V.0011 | C.A. LED CABLE BRYCE CANYON DVT | Vendor P/N : PCB0527T0001-5 |  |  | 1 | 1 | 1 | 1 | Cable | Cable | JPC |
|  | System | B50.01108.0001 | B50.01108.0001 | B50.01108.0001 | B50.01108.0001 | C.A. MINI SAS HD INT LS 270MM APH | Vendor P/N : HHS36-3470 AX4 |  |  |  |  | 1 |  | Cable | Cable | Amphenol |
|  | System | B42.0110C.0001 | B42.0110C.0001 | B42.0110C.0001 | B42.0110C.0001 | IOM CARD GUIDE MID BRCA KY | IOM CARD GUIDE MID TRITON KY |  | EVT opened tool | 1 | 1 | 1 | 1 | NYLON 66 /NA | Purchase | Kangyang |
|  | System | B42.0110D.0001 | B42.0110D.0001 | B42.0110D.0001 | B42.0110D.0001 | IOM CARD GUIDE SIDE BRCA KY | IOM CARD GUIDE SIDE TRITON KY |  | EVT opened tool | 2 | 2 | 2 | 2 | NYLON 66 /NA | Purchase | Kangyang |
|  | System |  | B34.01115.0001 | B34.01115.0001 | B34.01115.0001 | FAN GUARD BRCA | Fan guard |  |  | 4 | 4 | 2 | 2 |  | Purchase | Kangyang |
|  | System | B42.01103.0001 | B42.0111F.0001 | B42.0111F.0001 | B42.0111F.0001 | HLDR TRACK CABLE GULY-5AB-29F | TRACK CABLE HOLDER_GULY-5AB-29F |  |  | 1 | 1 | 1 | 1 |  | Purchase | Kangyang |
| MP 新增料 | System |  |  |  | B42.01118.0001 | CHASSIS LED CABLE CLIP | LED cable clip |  |  |  | 6 |  |  | Verdor PN: WLL-16 | Purchase | Kangyang |
| SA1031 | System |  | 086.000JM.0888 | 086.000JM.0888 | 086.000JM.0888 | SCRW TAP WAFER M5*L8 ZN | Screw_086.000JM.0888 |  |  | 16 | 16 | 8 | 8 | Screw | Purchase | 文豪 |
| SA1031 | System | 086.5A528.06R0 | 086.000J7.0586 | 086.000J7.0586 | 086.000J7.0586 | SCRW FLT M5X0.8 L6 NI NYLOK | SCREW_086.000J7.0586 |  |  | 4 | 4 | 4 | 4 | Screw | Purchase | 文豪 |
| SA1031 | System | 86.6C536.8R0 | 86.6C536.8R0 | 86.6C536.8R0 | 86.6C536.8R0 | SCRW M4X8 PH MS+E+N | M4X7.7PM+外齒華司-86.6C536.8R0 |  |  | 1 | 1 | 1 | 1 | Screw | Purchase | 文豪 |
|  | System | 86.00T32.544 | 86.00T32.544 | 86.00T32.544 | 86.00T32.544 | SCRW WAFRE M3.0 L4 NYLOK | SCREW_86.00T32.544 |  |  |  | 28 | 12 |  | Screw | Purchase | 文豪 |
| SA1031 | System | 86.1A522.5R0 | 086.000J9.0525 | 086.000J9.0525 | 086.000J9.0525 | SCRW PAN M2X0.4 L4.75 NI NYLOK | SCREW_086.000J9.0525 |  |  | 8 | 8 | 8 | 8 | Screw | Purchase | 文豪 |
| SA1031 | System | 86.5A534.4R0 | 86.00R06.644 | 86.00R06.644 | 86.00R06.644 | SCRW FLAT M3*L4 NYLOK | SCREW_86.00R06.644 |  |  | 10 | 10 | 10 | 10 | Screw | Purchase | 文豪 |
| SA1031 | System | 86.00Q25.547 | 86.00Q25.547 | 86.00Q25.547 | 86.00Q25.547 | SCRW CAP M3*5L NI NYLOK | SCREW_86.00Q25.547 |  |  | 24 | 24 | 24 | 24 | Screw | Purchase | 文豪 |
| SA1031 | System | 086.9A524.02R0 | 086.9A554.02R0 | 086.9A554.02R0 | 086.9A554.02R0 | SCRW WAFER M3X0.5 L2 NI NYLOK | SCREW_086.9A554.02R0 |  |  | 4 | 4 | 4 | 4 | Screw | Purchase | 文豪 |
|  | System |  | 86.5A364.8R0 | 86.5A364.8R0 | 86.5A364.8R0 | SCRW MACH FLAT M3*L8 BLACK ZN NYLOK | SCREW_86.5A364.8R0 |  |  | 6 |  |  | 6 | Screw | Purchase | 文豪 |
| SA1031 | System |  | 87.41242.420 | 87.41242.420 | 87.41242.420 | NUT M3 PLASMA |  |  |  | 6 |  |  | 6 | NUT | Purchase | 文豪 |
| SA1031 | System | 086.AA522.05R0 | 086.AA522.05R0 | 086.AA522.05R0 | 086.AA522.05R0 | SCRW TAP WEFER M2*L5 NI |  |  |  | 8 | 8 | 8 | 8 | SCREW | Purchase | 文豪 |
|  | System | B47.0111F.0001 | B47.0111F.0001 | B47.0111F.0001 | B47.0111F.0001 | MONOLAKE DUMMY BOARD | MONOLAKE DUMMY BOARD |  |  | 2 |  | 1 | 2 | Myalr+Sponge(E4308) | Purchase | 德竹 |
|  | System | B47.0110X.0001 | B47.0112H.0001 | B47.0112H.0001 | B47.0112H.0001 | MYLAR DPB SEAL DVT BC | Front DPB seal sponge |  |  | 1 | 1 | 1 | 1 | Myalr | Purchase | 德竹 |
|  | System | B40.0110H.0001 | B40.0110H.0001 | B40.0110H.0001 | B40.0110H.0001 | MYLAR DRAWER REAR WALL FAN BLOCK | MYLAY DRAWER REAR WALL FAN BLOCK |  |  |  |  | 2 | 2 | Sponge(E4382) | Purchase | 德竹 |
|  | System | B47.0111N.0001 | B47.0111N.0001 | B47.0111N.0001 | B47.0111N.0011 | MYLAR+SPONGE IOM M2 AIR BAFFLE BRCA | IOM M.2 Air Baffle |  |  |  | 2 |  |  | Myalr+Sponge(E4382) | Purchase | 德竹 |
| Following items are PCBA level ME BOM ,please ignore!!!!! |  |  |  |  |  |  |  |  |  |  |  |  |  |  |  |  |
| ` | F.DPB |  | 086.000IZ.0543 | 086.000IZ.0543 | 086.000LQ.0543 | THUMB SCREW PRESSFIT M3 L3 BC |  |  | DVT opened tool | 2 | 2 | 2 | 2 |  | Purchase | Fivetech |
|  | F.DPB |  | B42.0111I.0001 | B42.0111I.0001 | B42.0111I.1001 | CVR XCEDE PWR JX410-50728 MP | xcede_cover_B42_0111I_0001 |  | DVT opened tool | 1 | 1 | 1 | 1 | PP | Purchase | Kangyang |
|  | F.DPB |  | B42.0111M.0001 | B42.0111M.0001 | B42.0111M.1001 | CVR XCEDE SIGNAL JX412-50282 MP | xcede_cover_B42_0111M_0001 |  | DVT opened tool | 1 | 1 | 1 | 1 | PP | Purchase | Kangyang |
|  | F.DPB |  | B42.0111N.0001 | B42.0111N.0001 | B42.0111N.1001 | CVR XCEDE SIGNAL JX430-50035 MP | xcede_cover_B42_0111N_0001 |  | DVT opened tool | 2 | 2 | 2 | 2 | PP | Purchase | Kangyang |
| SA1031 | R.DPB |  | 086.1A554.0140 | 086.1A554.0140 | 086.1A554.0140 | SCRW PAN M3X0.5 L14 NI NYLOK |  |  |  | 2 | 2 | 2 | 2 | SCREW | Purchase | 文豪 |
| ` | R.DPB |  | 086.000IZ.0543 | 086.000IZ.0543 | 086.000LQ.0543 | THUMB SCREW PRESSFIT M3 L3 BC |  |  | DVT opened tool | 2 | 2 | 2 | 2 |  | Purchase | Fivetech |
|  | R.DPB |  | 87.41242.420 | 87.41242.420 | 87.41242.420 | NUT M3 PLASMA |  |  |  | 2 | 2 | 2 | 2 | NUT | Purchase | 文豪 |
|  | R.DPB |  | 088.0000E.0140 | 088.0000E.0140 | 088.0000E.0140 | WASH NYLON WS6-3.2-1 |  |  |  | 2 | 2 | 2 | 2 | Nylon(verdor PN:WS6-3.2-1) | Purchase | Kangyang |
|  | R.DPB |  | B42.0111J.0001 | B42.0111J.0001 | B42.0111J.1001 | CVR XCEDE PWR JX412-50194 MP | xcede_cover_B42_0111J_0001 |  | DVT opened tool | 1 |  |  |  | PP | Purchase | Kangyang |
|  | R.DPB |  | B42.0111L.0001 | B42.0111L.0001 | B42.0111L.1001 | CVR XCEDE SIGNAL JX410-50839 MP | xcede_cover_B42_0111L_0001 |  | DVT opened tool | 1 |  |  |  | PP | Purchase | Kangyang |
| SA1031 | SCC | YAS0-00054-000$001 | YAS0-00054-000$001 | YAS0-00054-000$001 | YAS0-00054-000$001 | SCREW TAPPING PAN M2 L5 BLUE ZN CR3+ |  |  |  | 4 | 4 | 4 | 4 | Screw | Purchase | 文豪 |
|  | SCC | B42.01108.0001 | B42.0111G.0001 | B42.0111G.0001 | B42.0111G.0011 | LATCH SCC R BRYCE CANYON MP |  |  | DVT opened tool | 2 | 2 | 2 | 2 | ASSY | Purchase | Fivetech |
|  | SCC | B42.0111B.0001 | B42.0111H.0001 | B42.0111H.0001 | B42.0111H.0011 | LATCH SCC L BRYCE CANYON MP |  |  | DVT opened tool | 2 | 2 | 2 | 2 | ASSY | Purchase | Fivetech |
|  | IOM(IOC,M.2) | B42.01109.0001 | B60.0110V.0001 | B60.0110V.0001 | B60.0110V.0011 | ASSY NIC CARD LATCH BC MP |  |  | DVT opened tool | 4 | 4 | 4 | 4 | Nylon 66 | Purchase | Fivetech |
|  | IOM(IOC,M.2) | B42.0110B.0001 | B42.0110B.0001 | B42.0110B.0001 | B42.0110B.0001 | SPACE SUPPORT BRCA KY | SPACE SUPPORT TRITON KY |  | EVT opened tool | 4 | 4 | 4 | 4 | NYLON 66 /NA | Purchase | Kangyang |
|  | IOM(IOC,M.2) |  | B42.0111K.0001 | B42.0111K.0001 | B42.0111K.1001 | CVR XCEDE SIGNAL JX410-50824 MP | xcede_cover_B42_0111K_0001 |  | DVT opened tool | 1 |  |  |  | PP | Purchase | Kangyang |
|  | IOM(IOC) | 086.6A322.04R5 | 086.6A322.04R5 | 086.6A322.04R5 | 086.6A322.04R5 | SCRW ROUND M2 L3 ZN |  |  |  |  |  | 2 |  | Screw | Purchase | 文豪 |
|  | IOM(M.2) | B42.01201.1001 | B42.01201.1011 | B42.01201.1011 | B42.01201.1011 | LATCH M.2 H3.9 FIVETECH 2 |  |  | EVT opened tool | 4 | 4 | 4 | 4 | Nylon 66 | Purchase | Fivetech |
